(kicad_pcb
	(version 20260206)
	(generator "pcbnew")
	(generator_version "10.0")
	(general
		(thickness 1.6)
		(legacy_teardrops no)
	)
	(paper "A4")
	(title_block
		(title "01162023_DA0F0TEBIF0_F0T_Expander_BD_F_brd_V02_OCP.brd")
		(comment 1 "Grand Teton / footprint 6602 of 9728 (PEX1), pads 2238-2358 of 2397")
	)
	(layers
		(0 "F.Cu" signal "TOP")
		(4 "In1.Cu" signal "GND")
		(6 "In2.Cu" signal "VCC")
		(8 "In3.Cu" signal "VCC1")
		(10 "In4.Cu" signal "GND1")
		(12 "In5.Cu" signal "IN1")
		(14 "In6.Cu" signal "GND2")
		(16 "In7.Cu" signal "IN2")
		(18 "In8.Cu" signal "GND3")
		(20 "In9.Cu" signal "IN3")
		(22 "In10.Cu" signal "GND4")
		(24 "In11.Cu" signal "IN4")
		(26 "In12.Cu" signal "GND5")
		(28 "In13.Cu" signal "IN5")
		(30 "In14.Cu" signal "GND6")
		(32 "In15.Cu" signal "IN6")
		(34 "In16.Cu" signal "GND7")
		(2 "B.Cu" signal "BOTTOM")
		(9 "F.Adhes" user "F.Adhesive")
		(11 "B.Adhes" user "B.Adhesive")
		(13 "F.Paste" user "Package Geometry/Pastemask Top")
		(15 "B.Paste" user "Package Geometry/Pastemask Bottom")
		(5 "F.SilkS" user "Ref Des/Silkscreen Top")
		(7 "B.SilkS" user "Ref Des/Silkscreen Bottom")
		(1 "F.Mask" user "Board Geometry/Soldermask Top")
		(3 "B.Mask" user "Board Geometry/Soldermask Bottom")
		(17 "Dwgs.User" user "User.Drawings")
		(19 "Cmts.User" user "User.Comments")
		(21 "Eco1.User" user "User.Eco1")
		(23 "Eco2.User" user "User.Eco2")
		(25 "Edge.Cuts" user "Board Geometry/Outline")
		(27 "Margin" user)
		(31 "F.CrtYd" user "Package Geometry/Place Bound Top")
		(29 "B.CrtYd" user "Package Geometry/Place Bound Bottom")
		(35 "F.Fab" user "Ref Des/Assembly Top")
		(33 "B.Fab" user "Ref Des/Assembly Bottom")
	)
	(footprint ""
		(layer "F.Cu")
		(at 175.749966 -295.89984)
		(property "Reference" "PEX1"
			(at -3.353562 35.593274 0)
			(unlocked yes)
			(layer "F.SilkS")
			(effects
				(font
					(size 2.032 1.524)
					(thickness 0.1524)
				)
				(justify left)
			)
		)
		(property "Value" ""
			(at 0 0 0)
			(layer "F.Fab")
			(effects
				(font
					(size 1.27 1.27)
				)
			)
		)
		(duplicate_pad_numbers_are_jumpers no)
		(pad "U37" smd circle
			(at 11.400028 -7.599934)
			(size 0.4572 0.4572)
			(layers "F.Cu" "F.Mask" "F.Paste")
			(net "GND")
		)
		(pad "U38" smd circle
			(at 12.349988 -7.599934)
			(size 0.4572 0.4572)
			(layers "F.Cu" "F.Mask" "F.Paste")
			(net "Net_5231")
		)
		(pad "U39" smd circle
			(at 13.299948 -7.599934)
			(size 0.4572 0.4572)
			(layers "F.Cu" "F.Mask" "F.Paste")
			(net "Net_5225")
		)
		(pad "U40" smd circle
			(at 14.249908 -7.599934)
			(size 0.4572 0.4572)
			(layers "F.Cu" "F.Mask" "F.Paste")
			(net "GND")
		)
		(pad "U41" smd circle
			(at 15.200122 -7.599934)
			(size 0.4572 0.4572)
			(layers "F.Cu" "F.Mask" "F.Paste")
			(net "GND")
		)
		(pad "U42" smd circle
			(at 16.150082 -7.599934)
			(size 0.4572 0.4572)
			(layers "F.Cu" "F.Mask" "F.Paste")
			(net "GND")
		)
		(pad "U43" smd circle
			(at 17.100042 -7.599934)
			(size 0.4572 0.4572)
			(layers "F.Cu" "F.Mask" "F.Paste")
			(net "Net_1436")
		)
		(pad "U44" smd circle
			(at 18.050002 -7.599934)
			(size 0.4572 0.4572)
			(layers "F.Cu" "F.Mask" "F.Paste")
			(net "Net_1427")
		)
		(pad "U45" smd circle
			(at 18.999962 -7.599934)
			(size 0.4572 0.4572)
			(layers "F.Cu" "F.Mask" "F.Paste")
			(net "GND")
		)
		(pad "U46" smd circle
			(at 19.949922 -7.599934)
			(size 0.4572 0.4572)
			(layers "F.Cu" "F.Mask" "F.Paste")
			(net "Net_1606")
		)
		(pad "U47" smd circle
			(at 20.899882 -7.599934)
			(size 0.4572 0.4572)
			(layers "F.Cu" "F.Mask" "F.Paste")
			(net "Net_1599")
		)
		(pad "U48" smd circle
			(at 21.850096 -7.599934)
			(size 0.4572 0.4572)
			(layers "F.Cu" "F.Mask" "F.Paste")
			(net "GND")
		)
		(pad "U49" smd circle
			(at 22.800056 -7.599934)
			(size 0.4572 0.4572)
			(layers "F.Cu" "F.Mask" "F.Paste")
			(net "GND")
		)
		(pad "V1" smd circle
			(at -22.800056 -6.649974)
			(size 0.4572 0.4572)
			(layers "F.Cu" "F.Mask" "F.Paste")
			(net "P5E_PEX1_STN7_RX_DN<113>")
		)
		(pad "V2" smd circle
			(at -21.850096 -6.649974)
			(size 0.4572 0.4572)
			(layers "F.Cu" "F.Mask" "F.Paste")
			(net "P5E_PEX1_STN7_RX_DP<113>")
		)
		(pad "V3" smd circle
			(at -20.899882 -6.649974)
			(size 0.4572 0.4572)
			(layers "F.Cu" "F.Mask" "F.Paste")
			(net "GND")
		)
		(pad "V4" smd circle
			(at -19.949922 -6.649974)
			(size 0.4572 0.4572)
			(layers "F.Cu" "F.Mask" "F.Paste")
			(net "GND")
		)
		(pad "V5" smd circle
			(at -18.999962 -6.649974)
			(size 0.4572 0.4572)
			(layers "F.Cu" "F.Mask" "F.Paste")
			(net "GND")
		)
		(pad "V6" smd circle
			(at -18.050002 -6.649974)
			(size 0.4572 0.4572)
			(layers "F.Cu" "F.Mask" "F.Paste")
			(net "GND")
		)
		(pad "V7" smd circle
			(at -17.100042 -6.649974)
			(size 0.4572 0.4572)
			(layers "F.Cu" "F.Mask" "F.Paste")
			(net "GND")
		)
		(pad "V8" smd circle
			(at -16.150082 -6.649974)
			(size 0.4572 0.4572)
			(layers "F.Cu" "F.Mask" "F.Paste")
			(net "P5E_PEX1_STN7_TX_DN<113>")
		)
		(pad "V9" smd circle
			(at -15.200122 -6.649974)
			(size 0.4572 0.4572)
			(layers "F.Cu" "F.Mask" "F.Paste")
			(net "P5E_PEX1_STN7_TX_DP<113>")
		)
		(pad "V10" smd circle
			(at -14.249908 -6.649974)
			(size 0.4572 0.4572)
			(layers "F.Cu" "F.Mask" "F.Paste")
			(net "GND")
		)
		(pad "V11" smd circle
			(at -13.299948 -6.649974)
			(size 0.4572 0.4572)
			(layers "F.Cu" "F.Mask" "F.Paste")
			(net "GND")
		)
		(pad "V12" smd circle
			(at -12.349988 -6.649974)
			(size 0.4572 0.4572)
			(layers "F.Cu" "F.Mask" "F.Paste")
			(net "GND")
		)
		(pad "V13" smd circle
			(at -11.400028 -6.649974)
			(size 0.4572 0.4572)
			(layers "F.Cu" "F.Mask" "F.Paste")
			(net "GND")
		)
		(pad "V14" smd circle
			(at -10.450068 -6.649974)
			(size 0.4572 0.4572)
			(layers "F.Cu" "F.Mask" "F.Paste")
			(net "P1V8_VDDA_PEX1")
		)
		(pad "V15" smd circle
			(at -9.500108 -6.649974)
			(size 0.4572 0.4572)
			(layers "F.Cu" "F.Mask" "F.Paste")
			(net "GND")
		)
		(pad "V16" smd circle
			(at -8.549894 -6.649974)
			(size 0.4572 0.4572)
			(layers "F.Cu" "F.Mask" "F.Paste")
			(net "P1V25_PEX1")
		)
		(pad "V17" smd circle
			(at -7.599934 -6.649974)
			(size 0.4572 0.4572)
			(layers "F.Cu" "F.Mask" "F.Paste")
			(net "P1V25_PEX1")
		)
		(pad "V18" smd circle
			(at -6.649974 -6.649974)
			(size 0.4572 0.4572)
			(layers "F.Cu" "F.Mask" "F.Paste")
			(net "P1V25_PEX1")
		)
		(pad "V19" smd circle
			(at -5.700014 -6.649974)
			(size 0.4572 0.4572)
			(layers "F.Cu" "F.Mask" "F.Paste")
			(net "P1V25_PEX1")
		)
		(pad "V20" smd circle
			(at -4.750054 -6.649974)
			(size 0.4572 0.4572)
			(layers "F.Cu" "F.Mask" "F.Paste")
			(net "P1V25_PEX1")
		)
		(pad "V21" smd circle
			(at -3.800094 -6.649974)
			(size 0.4572 0.4572)
			(layers "F.Cu" "F.Mask" "F.Paste")
			(net "P1V25_PEX1")
		)
		(pad "V22" smd circle
			(at -2.84988 -6.649974)
			(size 0.4572 0.4572)
			(layers "F.Cu" "F.Mask" "F.Paste")
			(net "P1V25_PEX1")
		)
		(pad "V23" smd circle
			(at -1.89992 -6.649974)
			(size 0.4572 0.4572)
			(layers "F.Cu" "F.Mask" "F.Paste")
			(net "P1V25_PEX1")
		)
		(pad "V24" smd circle
			(at -0.94996 -6.649974)
			(size 0.4572 0.4572)
			(layers "F.Cu" "F.Mask" "F.Paste")
			(net "P1V25_PEX1")
		)
		(pad "V25" smd circle
			(at 0 -6.649974)
			(size 0.4572 0.4572)
			(layers "F.Cu" "F.Mask" "F.Paste")
			(net "P1V25_PEX1")
		)
		(pad "V26" smd circle
			(at 0.94996 -6.649974)
			(size 0.4572 0.4572)
			(layers "F.Cu" "F.Mask" "F.Paste")
			(net "P1V25_PEX1")
		)
		(pad "V27" smd circle
			(at 1.89992 -6.649974)
			(size 0.4572 0.4572)
			(layers "F.Cu" "F.Mask" "F.Paste")
			(net "P1V25_PEX1")
		)
		(pad "V28" smd circle
			(at 2.84988 -6.649974)
			(size 0.4572 0.4572)
			(layers "F.Cu" "F.Mask" "F.Paste")
			(net "P1V25_PEX1")
		)
		(pad "V29" smd circle
			(at 3.800094 -6.649974)
			(size 0.4572 0.4572)
			(layers "F.Cu" "F.Mask" "F.Paste")
			(net "P1V25_PEX1")
		)
		(pad "V30" smd circle
			(at 4.750054 -6.649974)
			(size 0.4572 0.4572)
			(layers "F.Cu" "F.Mask" "F.Paste")
			(net "P1V25_PEX1")
		)
		(pad "V31" smd circle
			(at 5.700014 -6.649974)
			(size 0.4572 0.4572)
			(layers "F.Cu" "F.Mask" "F.Paste")
			(net "P1V25_PEX1")
		)
		(pad "V32" smd circle
			(at 6.649974 -6.649974)
			(size 0.4572 0.4572)
			(layers "F.Cu" "F.Mask" "F.Paste")
			(net "P1V25_PEX1")
		)
		(pad "V33" smd circle
			(at 7.599934 -6.649974)
			(size 0.4572 0.4572)
			(layers "F.Cu" "F.Mask" "F.Paste")
			(net "P1V25_PEX1")
		)
		(pad "V34" smd circle
			(at 8.549894 -6.649974)
			(size 0.4572 0.4572)
			(layers "F.Cu" "F.Mask" "F.Paste")
			(net "GND")
		)
		(pad "V35" smd circle
			(at 9.500108 -6.649974)
			(size 0.4572 0.4572)
			(layers "F.Cu" "F.Mask" "F.Paste")
			(net "P1V8_PEX")
		)
		(pad "V36" smd circle
			(at 10.450068 -6.649974)
			(size 0.4572 0.4572)
			(layers "F.Cu" "F.Mask" "F.Paste")
			(net "GND")
		)
		(pad "V37" smd circle
			(at 11.400028 -6.649974)
			(size 0.4572 0.4572)
			(layers "F.Cu" "F.Mask" "F.Paste")
			(net "GND")
		)
		(pad "V38" smd circle
			(at 12.349988 -6.649974)
			(size 0.4572 0.4572)
			(layers "F.Cu" "F.Mask" "F.Paste")
			(net "GND")
		)
		(pad "V39" smd circle
			(at 13.299948 -6.649974)
			(size 0.4572 0.4572)
			(layers "F.Cu" "F.Mask" "F.Paste")
			(net "VSENSE_P0V8_PEX1_SKT_VSEN")
		)
		(pad "V40" smd circle
			(at 14.249908 -6.649974)
			(size 0.4572 0.4572)
			(layers "F.Cu" "F.Mask" "F.Paste")
			(net "GND")
		)
		(pad "V41" smd circle
			(at 15.200122 -6.649974)
			(size 0.4572 0.4572)
			(layers "F.Cu" "F.Mask" "F.Paste")
			(net "Net_1362")
		)
		(pad "V42" smd circle
			(at 16.150082 -6.649974)
			(size 0.4572 0.4572)
			(layers "F.Cu" "F.Mask" "F.Paste")
			(net "Net_1394")
		)
		(pad "V43" smd circle
			(at 17.100042 -6.649974)
			(size 0.4572 0.4572)
			(layers "F.Cu" "F.Mask" "F.Paste")
			(net "GND")
		)
		(pad "V44" smd circle
			(at 18.050002 -6.649974)
			(size 0.4572 0.4572)
			(layers "F.Cu" "F.Mask" "F.Paste")
			(net "GND")
		)
		(pad "V45" smd circle
			(at 18.999962 -6.649974)
			(size 0.4572 0.4572)
			(layers "F.Cu" "F.Mask" "F.Paste")
			(net "GND")
		)
		(pad "V46" smd circle
			(at 19.949922 -6.649974)
			(size 0.4572 0.4572)
			(layers "F.Cu" "F.Mask" "F.Paste")
			(net "GND")
		)
		(pad "V47" smd circle
			(at 20.899882 -6.649974)
			(size 0.4572 0.4572)
			(layers "F.Cu" "F.Mask" "F.Paste")
			(net "GND")
		)
		(pad "V48" smd circle
			(at 21.850096 -6.649974)
			(size 0.4572 0.4572)
			(layers "F.Cu" "F.Mask" "F.Paste")
			(net "Net_1621")
		)
		(pad "V49" smd circle
			(at 22.800056 -6.649974)
			(size 0.4572 0.4572)
			(layers "F.Cu" "F.Mask" "F.Paste")
			(net "Net_1634")
		)
		(pad "W1" smd circle
			(at -22.800056 -5.700014)
			(size 0.4572 0.4572)
			(layers "F.Cu" "F.Mask" "F.Paste")
			(net "GND")
		)
		(pad "W2" smd circle
			(at -21.850096 -5.700014)
			(size 0.4572 0.4572)
			(layers "F.Cu" "F.Mask" "F.Paste")
			(net "GND")
		)
		(pad "W3" smd circle
			(at -20.899882 -5.700014)
			(size 0.4572 0.4572)
			(layers "F.Cu" "F.Mask" "F.Paste")
			(net "P5E_PEX1_STN7_RX_DN<112>")
		)
		(pad "W4" smd circle
			(at -19.949922 -5.700014)
			(size 0.4572 0.4572)
			(layers "F.Cu" "F.Mask" "F.Paste")
			(net "P5E_PEX1_STN7_RX_DP<112>")
		)
		(pad "W5" smd circle
			(at -18.999962 -5.700014)
			(size 0.4572 0.4572)
			(layers "F.Cu" "F.Mask" "F.Paste")
			(net "GND")
		)
		(pad "W6" smd circle
			(at -18.050002 -5.700014)
			(size 0.4572 0.4572)
			(layers "F.Cu" "F.Mask" "F.Paste")
			(net "P5E_PEX1_STN7_TX_DN<112>")
		)
		(pad "W7" smd circle
			(at -17.100042 -5.700014)
			(size 0.4572 0.4572)
			(layers "F.Cu" "F.Mask" "F.Paste")
			(net "P5E_PEX1_STN7_TX_DP<112>")
		)
		(pad "W8" smd circle
			(at -16.150082 -5.700014)
			(size 0.4572 0.4572)
			(layers "F.Cu" "F.Mask" "F.Paste")
			(net "GND")
		)
		(pad "W9" smd circle
			(at -15.200122 -5.700014)
			(size 0.4572 0.4572)
			(layers "F.Cu" "F.Mask" "F.Paste")
			(net "GND")
		)
		(pad "W10" smd circle
			(at -14.249908 -5.700014)
			(size 0.4572 0.4572)
			(layers "F.Cu" "F.Mask" "F.Paste")
			(net "GND")
		)
		(pad "W11" smd circle
			(at -13.299948 -5.700014)
			(size 0.4572 0.4572)
			(layers "F.Cu" "F.Mask" "F.Paste")
			(net "GND")
		)
		(pad "W12" smd circle
			(at -12.349988 -5.700014)
			(size 0.4572 0.4572)
			(layers "F.Cu" "F.Mask" "F.Paste")
			(net "GND")
		)
		(pad "W13" smd circle
			(at -11.400028 -5.700014)
			(size 0.4572 0.4572)
			(layers "F.Cu" "F.Mask" "F.Paste")
			(net "GND")
		)
		(pad "W14" smd circle
			(at -10.450068 -5.700014)
			(size 0.4572 0.4572)
			(layers "F.Cu" "F.Mask" "F.Paste")
			(net "GND")
		)
		(pad "W15" smd circle
			(at -9.500108 -5.700014)
			(size 0.4572 0.4572)
			(layers "F.Cu" "F.Mask" "F.Paste")
			(net "GND")
		)
		(pad "W16" smd circle
			(at -8.549894 -5.700014)
			(size 0.4572 0.4572)
			(layers "F.Cu" "F.Mask" "F.Paste")
			(net "GND")
		)
		(pad "W17" smd circle
			(at -7.599934 -5.700014)
			(size 0.4572 0.4572)
			(layers "F.Cu" "F.Mask" "F.Paste")
			(net "GND")
		)
		(pad "W18" smd circle
			(at -6.649974 -5.700014)
			(size 0.4572 0.4572)
			(layers "F.Cu" "F.Mask" "F.Paste")
			(net "GND")
		)
		(pad "W19" smd circle
			(at -5.700014 -5.700014)
			(size 0.4572 0.4572)
			(layers "F.Cu" "F.Mask" "F.Paste")
			(net "GND")
		)
		(pad "W20" smd circle
			(at -4.750054 -5.700014)
			(size 0.4572 0.4572)
			(layers "F.Cu" "F.Mask" "F.Paste")
			(net "GND")
		)
		(pad "W21" smd circle
			(at -3.800094 -5.700014)
			(size 0.4572 0.4572)
			(layers "F.Cu" "F.Mask" "F.Paste")
			(net "GND")
		)
		(pad "W22" smd circle
			(at -2.84988 -5.700014)
			(size 0.4572 0.4572)
			(layers "F.Cu" "F.Mask" "F.Paste")
			(net "GND")
		)
		(pad "W23" smd circle
			(at -1.89992 -5.700014)
			(size 0.4572 0.4572)
			(layers "F.Cu" "F.Mask" "F.Paste")
			(net "GND")
		)
		(pad "W24" smd circle
			(at -0.94996 -5.700014)
			(size 0.4572 0.4572)
			(layers "F.Cu" "F.Mask" "F.Paste")
			(net "GND")
		)
		(pad "W25" smd circle
			(at 0 -5.700014)
			(size 0.4572 0.4572)
			(layers "F.Cu" "F.Mask" "F.Paste")
			(net "GND")
		)
		(pad "W26" smd circle
			(at 0.94996 -5.700014)
			(size 0.4572 0.4572)
			(layers "F.Cu" "F.Mask" "F.Paste")
			(net "GND")
		)
		(pad "W27" smd circle
			(at 1.89992 -5.700014)
			(size 0.4572 0.4572)
			(layers "F.Cu" "F.Mask" "F.Paste")
			(net "GND")
		)
		(pad "W28" smd circle
			(at 2.84988 -5.700014)
			(size 0.4572 0.4572)
			(layers "F.Cu" "F.Mask" "F.Paste")
			(net "GND")
		)
		(pad "W29" smd circle
			(at 3.800094 -5.700014)
			(size 0.4572 0.4572)
			(layers "F.Cu" "F.Mask" "F.Paste")
			(net "GND")
		)
		(pad "W30" smd circle
			(at 4.750054 -5.700014)
			(size 0.4572 0.4572)
			(layers "F.Cu" "F.Mask" "F.Paste")
			(net "GND")
		)
		(pad "W31" smd circle
			(at 5.700014 -5.700014)
			(size 0.4572 0.4572)
			(layers "F.Cu" "F.Mask" "F.Paste")
			(net "GND")
		)
		(pad "W32" smd circle
			(at 6.649974 -5.700014)
			(size 0.4572 0.4572)
			(layers "F.Cu" "F.Mask" "F.Paste")
			(net "GND")
		)
		(pad "W33" smd circle
			(at 7.599934 -5.700014)
			(size 0.4572 0.4572)
			(layers "F.Cu" "F.Mask" "F.Paste")
			(net "GND")
		)
		(pad "W34" smd circle
			(at 8.549894 -5.700014)
			(size 0.4572 0.4572)
			(layers "F.Cu" "F.Mask" "F.Paste")
			(net "GND")
		)
		(pad "W35" smd circle
			(at 9.500108 -5.700014)
			(size 0.4572 0.4572)
			(layers "F.Cu" "F.Mask" "F.Paste")
			(net "P1V8_PEX")
		)
		(pad "W36" smd circle
			(at 10.450068 -5.700014)
			(size 0.4572 0.4572)
			(layers "F.Cu" "F.Mask" "F.Paste")
			(net "GND")
		)
		(pad "W37" smd circle
			(at 11.400028 -5.700014)
			(size 0.4572 0.4572)
			(layers "F.Cu" "F.Mask" "F.Paste")
			(net "GND")
		)
		(pad "W38" smd circle
			(at 12.349988 -5.700014)
			(size 0.4572 0.4572)
			(layers "F.Cu" "F.Mask" "F.Paste")
			(net "GND")
		)
		(pad "W39" smd circle
			(at 13.299948 -5.700014)
			(size 0.4572 0.4572)
			(layers "F.Cu" "F.Mask" "F.Paste")
			(net "VSENSE_P0V8_PEX1_SKT_VRTN")
		)
		(pad "W40" smd circle
			(at 14.249908 -5.700014)
			(size 0.4572 0.4572)
			(layers "F.Cu" "F.Mask" "F.Paste")
			(net "GND")
		)
		(pad "W41" smd circle
			(at 15.200122 -5.700014)
			(size 0.4572 0.4572)
			(layers "F.Cu" "F.Mask" "F.Paste")
			(net "GND")
		)
		(pad "W42" smd circle
			(at 16.150082 -5.700014)
			(size 0.4572 0.4572)
			(layers "F.Cu" "F.Mask" "F.Paste")
			(net "GND")
		)
		(pad "W43" smd circle
			(at 17.100042 -5.700014)
			(size 0.4572 0.4572)
			(layers "F.Cu" "F.Mask" "F.Paste")
			(net "Net_1407")
		)
		(pad "W44" smd circle
			(at 18.050002 -5.700014)
			(size 0.4572 0.4572)
			(layers "F.Cu" "F.Mask" "F.Paste")
			(net "Net_1366")
		)
		(pad "W45" smd circle
			(at 18.999962 -5.700014)
			(size 0.4572 0.4572)
			(layers "F.Cu" "F.Mask" "F.Paste")
			(net "GND")
		)
		(pad "W46" smd circle
			(at 19.949922 -5.700014)
			(size 0.4572 0.4572)
			(layers "F.Cu" "F.Mask" "F.Paste")
			(net "Net_1631")
		)
		(pad "W47" smd circle
			(at 20.899882 -5.700014)
			(size 0.4572 0.4572)
			(layers "F.Cu" "F.Mask" "F.Paste")
			(net "Net_1618")
		)
		(pad "W48" smd circle
			(at 21.850096 -5.700014)
			(size 0.4572 0.4572)
			(layers "F.Cu" "F.Mask" "F.Paste")
			(net "GND")
		)
		(pad "W49" smd circle
			(at 22.800056 -5.700014)
			(size 0.4572 0.4572)
			(layers "F.Cu" "F.Mask" "F.Paste")
			(net "GND")
		)
		(pad "Y1" smd circle
			(at -22.800056 -4.750054)
			(size 0.4572 0.4572)
			(layers "F.Cu" "F.Mask" "F.Paste")
			(net "GND")
		)
		(pad "Y2" smd circle
			(at -21.850096 -4.750054)
			(size 0.4572 0.4572)
			(layers "F.Cu" "F.Mask" "F.Paste")
			(net "GND")
		)
		(pad "Y3" smd circle
			(at -20.899882 -4.750054)
			(size 0.4572 0.4572)
			(layers "F.Cu" "F.Mask" "F.Paste")
			(net "GND")
		)
		(pad "Y4" smd circle
			(at -19.949922 -4.750054)
			(size 0.4572 0.4572)
			(layers "F.Cu" "F.Mask" "F.Paste")
			(net "GND")
		)
		(pad "Y5" smd circle
			(at -18.999962 -4.750054)
			(size 0.4572 0.4572)
			(layers "F.Cu" "F.Mask" "F.Paste")
			(net "GND")
		)
		(pad "Y6" smd circle
			(at -18.050002 -4.750054)
			(size 0.4572 0.4572)
			(layers "F.Cu" "F.Mask" "F.Paste")
			(net "GND")
		)
		(pad "Y7" smd circle
			(at -17.100042 -4.750054)
			(size 0.4572 0.4572)
			(layers "F.Cu" "F.Mask" "F.Paste")
			(net "GND")
		)
		(pad "Y8" smd circle
			(at -16.150082 -4.750054)
			(size 0.4572 0.4572)
			(layers "F.Cu" "F.Mask" "F.Paste")
			(net "GND")
		)
		(pad "Y9" smd circle
			(at -15.200122 -4.750054)
			(size 0.4572 0.4572)
			(layers "F.Cu" "F.Mask" "F.Paste")
			(net "GND")
		)
		(pad "Y10" smd circle
			(at -14.249908 -4.750054)
			(size 0.4572 0.4572)
			(layers "F.Cu" "F.Mask" "F.Paste")
			(net "GND")
		)
	)
)
